# S9S_MB_2U (Grand Teton) — schematic netlist excerpt (pin names and nets, part order shuffled) for the footprints in the layout excerpt that follows; sources: Cadence DE-HDL packaged netlist, KiCad conversion of 03242023_DA0F0TMBIJ0_F0T_Motherboard_J_brd_V01_OCP.brd

PR325  Q_RES  8.87K 1% EMPTY  pkg 0402LF  page 285 : A = PVCCIN_CPU1_LSET2 ; B = GND
R1263  Q_RES  33.2 1% CHIP  pkg 0402LF  page 203 : A = FM_PLT_BMC_THERMTRIP_R_N ; B = FM_PCH_BMC_THERMTRIP_N

(kicad_pcb
	(version 20260206)
	(generator "pcbnew")
	(generator_version "10.0")
	(general
		(thickness 1.6)
		(legacy_teardrops no)
	)
	(paper "A4")
	(title_block
		(title "03242023_DA0F0TMBIJ0_F0T_Motherboard_J_brd_V01_OCP.brd")
		(comment 1 "Grand Teton / footprints 486-487 of 6105")
	)
	(layers
		(0 "F.Cu" signal "TOP")
		(4 "In1.Cu" signal "GND")
		(6 "In2.Cu" signal "IN1")
		(8 "In3.Cu" signal "GND1")
		(10 "In4.Cu" signal "IN2")
		(12 "In5.Cu" signal "GND2")
		(14 "In6.Cu" signal "IN3")
		(16 "In7.Cu" signal "GND3")
		(18 "In8.Cu" signal "VCC")
		(20 "In9.Cu" signal "VCC1")
		(22 "In10.Cu" signal "GND4")
		(24 "In11.Cu" signal "IN4")
		(26 "In12.Cu" signal "GND5")
		(28 "In13.Cu" signal "IN5")
		(30 "In14.Cu" signal "GND6")
		(32 "In15.Cu" signal "IN6")
		(34 "In16.Cu" signal "GND7")
		(2 "B.Cu" signal "BOTTOM")
		(9 "F.Adhes" user "F.Adhesive")
		(11 "B.Adhes" user "B.Adhesive")
		(13 "F.Paste" user "Package Geometry/Pastemask Top")
		(15 "B.Paste" user "Package Geometry/Pastemask Bottom")
		(5 "F.SilkS" user "Ref Des/Silkscreen Top")
		(7 "B.SilkS" user "Ref Des/Silkscreen Bottom")
		(1 "F.Mask" user "Board Geometry/Soldermask Top")
		(3 "B.Mask" user "Board Geometry/Soldermask Bottom")
		(17 "Dwgs.User" user "User.Drawings")
		(19 "Cmts.User" user "User.Comments")
		(21 "Eco1.User" user "User.Eco1")
		(23 "Eco2.User" user "User.Eco2")
		(25 "Edge.Cuts" user "Board Geometry/Outline")
		(27 "Margin" user)
		(31 "F.CrtYd" user "Package Geometry/Place Bound Top")
		(29 "B.CrtYd" user "Package Geometry/Place Bound Bottom")
		(35 "F.Fab" user "Ref Des/Assembly Top")
		(33 "B.Fab" user "Ref Des/Assembly Bottom")
	)
	(footprint ""
		(layer "F.Cu")
		(at 315.110622 -52.288948 180)
		(property "Reference" "R1263"
			(at 0 0 180)
			(layer "F.SilkS")
			(hide yes)
			(effects
				(font
					(size 1.27 1.27)
				)
			)
		)
		(property "Value" ""
			(at 0 0 180)
			(layer "F.Fab")
			(effects
				(font
					(size 1.27 1.27)
				)
			)
		)
		(duplicate_pad_numbers_are_jumpers no)
		(fp_line
			(start 0.7874 0.4064)
			(end -0.7874 0.4064)
			(stroke
				(width 0.1524)
				(type default)
			)
			(layer "F.SilkS")
		)
		(fp_line
			(start 0.7874 -0.4064)
			(end 0.7874 0.4064)
			(stroke
				(width 0.1524)
				(type default)
			)
			(layer "F.SilkS")
		)
		(fp_line
			(start -0.7874 0.4064)
			(end -0.7874 -0.4064)
			(stroke
				(width 0.1524)
				(type default)
			)
			(layer "F.SilkS")
		)
		(fp_line
			(start -0.7874 -0.4064)
			(end 0.7874 -0.4064)
			(stroke
				(width 0.1524)
				(type default)
			)
			(layer "F.SilkS")
		)
		(fp_line
			(start 0.67945 0.3048)
			(end 0.120396 0.3048)
			(stroke
				(width 0.1)
				(type default)
			)
			(layer "F.Fab")
		)
		(fp_line
			(start 0.67945 -0.3048)
			(end 0.67945 0.3048)
			(stroke
				(width 0.1)
				(type default)
			)
			(layer "F.Fab")
		)
		(fp_line
			(start 0.12065 -0.2794)
			(end 0.12065 -0.3048)
			(stroke
				(width 0.1)
				(type default)
			)
			(layer "F.Fab")
		)
		(fp_line
			(start 0.12065 -0.3048)
			(end 0.67945 -0.3048)
			(stroke
				(width 0.1)
				(type default)
			)
			(layer "F.Fab")
		)
		(fp_line
			(start 0.120396 0.3048)
			(end 0.120396 0.2794)
			(stroke
				(width 0.1)
				(type default)
			)
			(layer "F.Fab")
		)
		(fp_line
			(start 0.120396 0.2794)
			(end -0.12065 0.2794)
			(stroke
				(width 0.1)
				(type default)
			)
			(layer "F.Fab")
		)
		(fp_line
			(start -0.12065 0.3048)
			(end -0.67945 0.3048)
			(stroke
				(width 0.1)
				(type default)
			)
			(layer "F.Fab")
		)
		(fp_line
			(start -0.12065 0.2794)
			(end -0.12065 0.3048)
			(stroke
				(width 0.1)
				(type default)
			)
			(layer "F.Fab")
		)
		(fp_line
			(start -0.12065 -0.2794)
			(end 0.12065 -0.2794)
			(stroke
				(width 0.1)
				(type default)
			)
			(layer "F.Fab")
		)
		(fp_line
			(start -0.12065 -0.305054)
			(end -0.12065 -0.2794)
			(stroke
				(width 0.1)
				(type default)
			)
			(layer "F.Fab")
		)
		(fp_line
			(start -0.67945 0.3048)
			(end -0.67945 -0.305054)
			(stroke
				(width 0.1)
				(type default)
			)
			(layer "F.Fab")
		)
		(fp_line
			(start -0.67945 -0.305054)
			(end -0.12065 -0.305054)
			(stroke
				(width 0.1)
				(type default)
			)
			(layer "F.Fab")
		)
		(pad "1" smd circle
			(at -0.40005 0 180)
			(size 0 0)
			(layers "F.Cu" "F.Mask" "F.Paste")
			(net "FM_PLT_BMC_THERMTRIP_R_N")
		)
		(pad "2" smd circle
			(at 0.40005 0 180)
			(size 0 0)
			(layers "F.Cu" "F.Mask" "F.Paste")
			(net "FM_PCH_BMC_THERMTRIP_N")
		)
	)
	(footprint ""
		(layer "F.Cu")
		(at 104.277922 -338.86013)
		(property "Reference" "PR325"
			(at 0 0 0)
			(layer "F.SilkS")
			(hide yes)
			(effects
				(font
					(size 1.27 1.27)
				)
			)
		)
		(property "Value" ""
			(at 0 0 0)
			(layer "F.Fab")
			(effects
				(font
					(size 1.27 1.27)
				)
			)
		)
		(duplicate_pad_numbers_are_jumpers no)
		(fp_line
			(start -0.7874 -0.4064)
			(end 0.7874 -0.4064)
			(stroke
				(width 0.1524)
				(type default)
			)
			(layer "F.SilkS")
		)
		(fp_line
			(start -0.7874 0.4064)
			(end -0.7874 -0.4064)
			(stroke
				(width 0.1524)
				(type default)
			)
			(layer "F.SilkS")
		)
		(fp_line
			(start 0.7874 -0.4064)
			(end 0.7874 0.4064)
			(stroke
				(width 0.1524)
				(type default)
			)
			(layer "F.SilkS")
		)
		(fp_line
			(start 0.7874 0.4064)
			(end -0.7874 0.4064)
			(stroke
				(width 0.1524)
				(type default)
			)
			(layer "F.SilkS")
		)
		(fp_line
			(start -0.67945 -0.305054)
			(end -0.12065 -0.305054)
			(stroke
				(width 0.1)
				(type default)
			)
			(layer "F.Fab")
		)
		(fp_line
			(start -0.67945 0.3048)
			(end -0.67945 -0.305054)
			(stroke
				(width 0.1)
				(type default)
			)
			(layer "F.Fab")
		)
		(fp_line
			(start -0.12065 -0.305054)
			(end -0.12065 -0.2794)
			(stroke
				(width 0.1)
				(type default)
			)
			(layer "F.Fab")
		)
		(fp_line
			(start -0.12065 -0.2794)
			(end 0.12065 -0.2794)
			(stroke
				(width 0.1)
				(type default)
			)
			(layer "F.Fab")
		)
		(fp_line
			(start -0.12065 0.2794)
			(end -0.12065 0.3048)
			(stroke
				(width 0.1)
				(type default)
			)
			(layer "F.Fab")
		)
		(fp_line
			(start -0.12065 0.3048)
			(end -0.67945 0.3048)
			(stroke
				(width 0.1)
				(type default)
			)
			(layer "F.Fab")
		)
		(fp_line
			(start 0.120396 0.2794)
			(end -0.12065 0.2794)
			(stroke
				(width 0.1)
				(type default)
			)
			(layer "F.Fab")
		)
		(fp_line
			(start 0.120396 0.3048)
			(end 0.120396 0.2794)
			(stroke
				(width 0.1)
				(type default)
			)
			(layer "F.Fab")
		)
		(fp_line
			(start 0.12065 -0.3048)
			(end 0.67945 -0.3048)
			(stroke
				(width 0.1)
				(type default)
			)
			(layer "F.Fab")
		)
		(fp_line
			(start 0.12065 -0.2794)
			(end 0.12065 -0.3048)
			(stroke
				(width 0.1)
				(type default)
			)
			(layer "F.Fab")
		)
		(fp_line
			(start 0.67945 -0.3048)
			(end 0.67945 0.3048)
			(stroke
				(width 0.1)
				(type default)
			)
			(layer "F.Fab")
		)
		(fp_line
			(start 0.67945 0.3048)
			(end 0.120396 0.3048)
			(stroke
				(width 0.1)
				(type default)
			)
			(layer "F.Fab")
		)
		(pad "1" smd circle
			(at -0.40005 0)
			(size 0 0)
			(layers "F.Cu" "F.Mask" "F.Paste")
			(net "PVCCIN_CPU1_LSET2")
		)
		(pad "2" smd circle
			(at 0.40005 0)
			(size 0 0)
			(layers "F.Cu" "F.Mask" "F.Paste")
			(net "GND")
		)
	)
)
